FILE_TYPE = CONNECTIVITY;
{Allegro Design Entry HDL 16.6-p007 (v16-6-112F) 10/10/2012}
"PAGE_NUMBER" = 223;
0"NC";
1"P3V3_STBY\g";
2"GND\g";
3"GND\g";
4"GND\g";
5"P3V3_STBY\g";
6"GND\g";
7"GND\g";
8"GND\g";
9"GND\g";
10"GND\g";
11"GND\g";
12"PVCCIO_CPU1\g";
13"VR_FET_SW_P12V_STBY_PVDDQ_GHJ\g";
14"GND\g";
15"GND\g";
16"PVCCIO_CPU1\g";
17"GND\g";
18"GND\g";
19"VSENSE_PVDDQ_GHJ_N";
20"VR_PVDDQ_GHJ_VD12";
21"IRQ_PVDDQ_GHJ_VRHOT_LVT3_N";
22"PWRGD_PVDDQ_GHJ";
23"SMB_VR_STBY_LVC3_SCL";
24"PWRGD_PVDDQ_GHJ_R";
25"IRQ_PVDDQ_GHJ_VRHOT_LVT3_R_N";
26"SVID_ALERT1_CPU1_R_N";
27"SVID_DIO1_CPU1_R";
28"PU_VR_PVDDQ_GHJ_FAULT1";
29"SMB_VR_STBY_LVC3_SDA";
30"SVID_ALERT_PVDDQ_GHJ";
31"TP_PVDDQ_GHJ_MP2";
32"TP_PVDDQ_GHJ_BPWM1";
33"TP_PVDDQ_GHJ_PWM3";
34"SMB_VR_SDA_VDDQ_GHJ";
35"SMB_VR_SCL_VDDQ_GHJ";
36"SVID_VDIO_PVDDQ_GHJ";
37"NC_PVDDQ_GHJ_DNC0";
38"NC_PVDDQ_GHJ_DNC1";
39"NC_PVDDQ_GHJ_PINALRT_N";
40"TP_PVDDQ_GHJ_MP1";
41"VR_PVDDQ_GHJ_VD12";
42"VR_PVDDQ_GHJ_PWM1";
43"VR_PVDDQ_GHJ_PWM2";
44"VR_PVDDQ_GHJ_VDD";
45"SVID_CLK_PVDDQ_GHJ";
46"TP_PVDDQ_GHJ_PH3_IMON";
47"TP_PVDDQ_GHJ_PH3_IMON_REF";
48"VR_PVDDQ_GHJ_VREN";
49"A_TSENSE_PVDDQ_GHJ";
50"VR_PVDDQ_GHJ_XADDR1";
51"TP_PVDDQ_GHJ_BREF1";
52"TP_PVDDQ_GHJ_BVREF";
53"TP_PVDDQ_GHJ_BVSEN";
54"TP_PVDDQ_GHJ_RESET_N";
55"VR_PVDDQ_GHJ_XADDR2";
56"TP_PVDDQ_GHJ_BTSEN";
57"VR_PVDDQ_GHJ_AVSP";
58"VR_PVDDQ_GHJ_AIREF1";
59"VR_PVDDQ_GHJ_AIREF2";
60"VR_PVDDQ_GHJ_AIINSEN";
61"ISENSE_PVDDQ_GHJ_PH1_IMON";
62"ISENSE_PVDDQ_GHJ_PH2_IMON";
63"VR_PVDDQ_GHJ_VINSEN";
64"SVID_CLK1_CPU1_R";
65"VR_PVDDQ_GHJ_VD12";
66"VR_PVDDQ_GHJ_VINSEN";
67"VSENSE_PVDDQ_GHJ_P";
68"FM_PVDDQ_GHJ_EN";
%"RES"
"2","(2700,3100)","0","mstr_discrete","I13";
;
CDS_SEC"1"
SEC_TYPE"0402"
SEC"1"
CDS_LOCATION"R1G6"
CDS_LIB"mstr_discrete"
ROOM"VDDQ_GHJ_PWR_VR"
LOCATION"R1G6"
VALUE"2.26K"
TOLERANCE"1.0%"
WATTAGE"1/16W"
MATERIAL"EMPTY"
PART_NUMBER"G21796-311"
PACK_TYPE"0402";
"A"
$PN"1"1;
"B"
$PN"2"28;
%"RES"
"1","(3275,2550)","0","mstr_discrete","I14";
;
CDS_SEC"1"
$SEC"1"
CDS_LOCATION"R1G12"
ROOM"VDDQ_GHJ_PWR_VR"
CDS_LIB"mstr_discrete"
LOCATION"R1G12"
PART_NUMBER"G21796-250"
VALUE"22.1"
MATERIAL"CHIP"
TOLERANCE"1.0%"
PACK_TYPE"0402"
WATTAGE"1/16W";
"B"
$PN"2"22;
"A"
$PN"1"24;
%"P3V3_STBY"
"1","(2475,3800)","0","mstr_symbols","I15";
;
VOLTAGE"3.3V"
SIZE"1B"
CDS_LIB"mstr_symbols"
BODY_TYPE"PLUMBING"
HDL_POWER"P3V3_STBY";
"G\NAC"1;
%"RES"
"1","(2875,2400)","0","mstr_discrete","I16";
;
CDS_SEC"1"
SEC_TYPE"0402"
SEC"1"
CDS_LIB"mstr_discrete"
CDS_LOCATION"R1G9"
ROOM"VDDQ_GHJ_PWR_VR"
MATERIAL"CHIP"
PACK_TYPE"0402"
LOCATION"R1G9"
TOLERANCE"5%"
PART_NUMBER"G21497-005"
VALUE"0.0"
WATTAGE"1/16W";
"B"
$PN"2"26;
"A"
$PN"1"30;
%"RES"
"2","(2400,3100)","0","mstr_discrete","I17";
;
CDS_SEC"1"
SEC"1"
SEC_TYPE"0402"
ROOM"VDDQ_GHJ_PWR_VR"
CDS_LOCATION"R1G16"
CDS_LIB"mstr_discrete"
LOCATION"R1G16"
VALUE"1.00K"
WATTAGE"1/16W"
TOLERANCE"1%"
PART_NUMBER"G21796-026"
MATERIAL"CHIP"
PACK_TYPE"0402";
"A"
$PN"1"1;
"B"
$PN"2"24;
%"RES"
"1","(3175,2050)","0","mstr_discrete","I21";
;
CDS_SEC"1"
$SEC"1"
CDS_LOCATION"R1G19"
ROOM"VDDQ_GHJ_PWR_VR"
CDS_LIB"mstr_discrete"
PART_NUMBER"G21497-005"
LOCATION"R1G19"
TOLERANCE"5%"
PACK_TYPE"0402"
MATERIAL"CHIP"
VALUE"0.0"
WATTAGE"1/16W";
"B"
$PN"2"23;
"A"
$PN"1"35;
%"RES"
"1","(2850,2000)","0","mstr_discrete","I22";
;
ROOM"VDDQ_GHJ_PWR_VR"
$SEC"1"
CDS_SEC"1"
CDS_LOCATION"R1G21"
CDS_LIB"mstr_discrete"
PART_NUMBER"G21497-005"
LOCATION"R1G21"
TOLERANCE"5%"
PACK_TYPE"0402"
MATERIAL"CHIP"
VALUE"0.0"
WATTAGE"1/16W";
"B"
$PN"2"29;
"A"
$PN"1"34;
%"RES"
"1","(2850,1700)","0","mstr_discrete","I23";
;
CDS_SEC"1"
CDS_LIB"mstr_discrete"
ROOM"VDDQ_GHJ_PWR_VR"
SEC"1"
SEC_TYPE"0402"
CDS_LOCATION"R1G10"
PACK_TYPE"0402"
MATERIAL"CHIP"
LOCATION"R1G10"
PART_NUMBER"G21497-005"
TOLERANCE"5%"
WATTAGE"1/16W"
VALUE"0.0";
"B"
$PN"2"27;
"A"
$PN"1"36;
%"GND"
"1","(2075,825)","0","mstr_symbols","I24";
;
HDL_POWER"GND"
CDS_LIB"mstr_symbols"
SIZE"1B"
VOLTAGE"0"
BODY_TYPE"PLUMBING"
ROOM"VDDQ_GHJ_PWR_VR";
"A\NAC"2;
%"CAP_A"
"1","(1600,3100)","0","dev_discrete","I25";
;
$SEC"1"
CDS_SEC"1"
ROOM"VDDQ_GHJ_PWR_VR"
CDS_LIB"dev_discrete"
CDS_LOCATION"C1G27"
LOCATION"C1G27"
VALUE"1.0UF"
VOLTAGE"6.3V"
TOLERANCE"10%"
PACK_TYPE"0402V"
PART_NUMBER"D97712-004"
MATERIAL"X6S";
"B"
$PN"2"3;
"A"
$PN"1"44;
%"GND"
"1","(1600,2900)","0","mstr_symbols","I26";
;
HDL_POWER"GND"
SIZE"1B"
BODY_TYPE"PLUMBING"
CDS_LIB"mstr_symbols"
VOLTAGE"0"
ROOM"VDDQ_GHJ_PWR_VR";
"A\NAC"3;
%"CAP_A"
"1","(1200,3100)","0","dev_discrete","I27";
;
SEC_TYPE"0402V"
SEC"1"
CDS_SEC"1"
ROOM"VDDQ_GHJ_PWR_VR"
CDS_LOCATION"C1G25"
CDS_LIB"dev_discrete"
LOCATION"C1G25"
VALUE"0.1UF"
VOLTAGE"16V"
TOLERANCE"10%"
PART_NUMBER"A36096-030"
PACK_TYPE"0402V"
MATERIAL"X7R";
"B"
$PN"2"4;
"A"
$PN"1"44;
%"GND"
"1","(1200,2900)","0","mstr_symbols","I28";
;
HDL_POWER"GND"
VOLTAGE"0"
SIZE"1B"
CDS_LIB"mstr_symbols"
BODY_TYPE"PLUMBING"
ROOM"VDDQ_GHJ_PWR_VR";
"A\NAC"4;
%"P3V3_STBY"
"1","(900,3775)","0","mstr_symbols","I29";
;
SIZE"1B"
CDS_LIB"mstr_symbols"
BODY_TYPE"PLUMBING"
VOLTAGE"3.3V"
HDL_POWER"P3V3_STBY";
"G\NAC"5;
%"RES"
"2","(900,3450)","0","mstr_discrete","I30";
;
CDS_SEC"1"
SEC_TYPE"0402"
SEC"1"
ROOM"VDDQ_GHJ_PWR_VR"
CDS_LOCATION"R9U10"
CDS_LIB"mstr_discrete"
LOCATION"R9U10"
PART_NUMBER"G21497-005"
VALUE"0.0"
PACK_TYPE"0402"
MATERIAL"CHIP"
WATTAGE"1/16W"
TOLERANCE"5%";
"A"
$PN"1"5;
"B"
$PN"2"44;
%"RES"
"1","(-1725,1075)","0","mstr_discrete","I32";
;
CDS_SEC"1"
SEC"1"
SEC_TYPE"0402"
NO_XNET_CONNECTION"1"
ROOM"VDDQ_GHJ_PWR_VR"
CDS_LOCATION"R1G5"
CDS_LIB"mstr_discrete"
LOCATION"R1G5"
PART_NUMBER"G21796-066"
VALUE"10.0"
TOLERANCE"1%"
PACK_TYPE"0402"
MATERIAL"CHIP"
WATTAGE"1/16W";
"B"
$PN"2"57;
"A"
$PN"1"67;
%"GND"
"1","(175,850)","0","mstr_symbols","I35";
;
HDL_POWER"GND"
SIZE"1B"
CDS_LIB"mstr_symbols"
VOLTAGE"0"
BODY_TYPE"PLUMBING"
ROOM"VDDQ_GHJ_PWR_VR";
"A\NAC"6;
%"CAP"
"1","(100,750)","2","mstr_discrete","I36";
;
CDS_SEC"1"
CDS_LOCATION"C1G24"
SEC"1"
ROOM"VDDQ_GHJ_PWR_VR"
SEC_TYPE"0402LF"
CDS_LIB"mstr_discrete"
LOCATION"C1G24"
PART_NUMBER"A36096-050"
VALUE"220PF"
PACK_TYPE"0402LF"
VOLTAGE"50V"
TOLERANCE"10%"
MATERIAL"X7R";
"A"
$PN"1"49;
"B"
$PN"2"11;
%"CAP"
"1","(-1450,925)","0","mstr_discrete","I39";
;
CDS_SEC"1"
SEC"1"
CDS_LOCATION"C1G16"
SEC_TYPE"0402LF"
ROOM"VDDQ_GHJ_PWR_VR"
NO_XNET_CONNECTION"1"
CDS_LIB"mstr_discrete"
LOCATION"C1G16"
MATERIAL"X7R"
TOLERANCE"10%"
PACK_TYPE"0402LF"
VALUE"220PF"
PART_NUMBER"A36096-050"
VOLTAGE"50V";
"A"
$PN"1"57;
"B"
$PN"2"19;
%"CAP_A"
"1","(3775,125)","0","dev_discrete","I41";
;
ROOM"VDDQ_GHJ_PWR_VR"
$SEC"1"
CDS_SEC"1"
CDS_LIB"dev_discrete"
CDS_LOCATION"C1G23"
LOCATION"C1G23"
VALUE"1.0UF"
TOLERANCE"10%"
VOLTAGE"6.3V"
MATERIAL"X6S"
PART_NUMBER"D97712-004"
PACK_TYPE"0402V";
"B"
$PN"2"7;
"A"
$PN"1"20;
%"GND"
"1","(3775,-175)","0","mstr_symbols","I42";
;
HDL_POWER"GND"
VOLTAGE"0"
SIZE"1B"
CDS_LIB"mstr_symbols"
BODY_TYPE"PLUMBING"
ROOM"VDDQ_GHJ_PWR_VR";
"A\NAC"7;
%"GND"
"1","(3375,-75)","0","mstr_symbols","I43";
;
HDL_POWER"GND"
ROOM"VDDQ_GHJ_PWR_VR"
BODY_TYPE"PLUMBING"
CDS_LIB"mstr_symbols"
SIZE"1B"
VOLTAGE"0";
"A\NAC"8;
%"CAP_A"
"1","(3375,125)","0","dev_discrete","I44";
;
SEC"1"
ROOM"VDDQ_GHJ_PWR_VR"
CDS_SEC"1"
SEC_TYPE"0402V"
CDS_LIB"dev_discrete"
CDS_LOCATION"C1G22"
MATERIAL"X7R"
VOLTAGE"16V"
LOCATION"C1G22"
VALUE"0.1UF"
TOLERANCE"10%"
PART_NUMBER"A36096-030"
PACK_TYPE"0402V";
"B"
$PN"2"8;
"A"
$PN"1"20;
%"GND"
"1","(625,50)","0","mstr_symbols","I46";
;
HDL_POWER"GND"
BODY_TYPE"PLUMBING"
CDS_LIB"mstr_symbols"
VOLTAGE"0"
ROOM"VDDQ_GHJ_PWR_VR"
SIZE"1B";
"A\NAC"9;
%"GND"
"1","(275,50)","0","mstr_symbols","I47";
;
HDL_POWER"GND"
CDS_LIB"mstr_symbols"
VOLTAGE"0"
BODY_TYPE"PLUMBING"
SIZE"1B"
ROOM"VDDQ_GHJ_PWR_VR";
"A\NAC"10;
%"GND"
"1","(100,50)","0","mstr_symbols","I48";
;
VOLTAGE"0"
CDS_LIB"mstr_symbols"
BODY_TYPE"PLUMBING"
HDL_POWER"GND"
SIZE"1B"
ROOM"VDDQ_GHJ_PWR_VR";
"A\NAC"11;
%"PVCCIO_CPU1"
"1","(-625,3925)","0","mstr_symbols","I49";
;
VOLTAGE"1.1V"
CDS_LIB"mstr_symbols"
BODY_TYPE"PLUMBING"
HDL_POWER"PVCCIO_CPU1";
"G\NAC"12;
%"RES"
"2","(-625,3350)","0","mstr_discrete","I50";
;
CDS_SEC"1"
SEC_TYPE"0402"
SEC"1"
CDS_LOCATION"R9U4"
ROOM"VDDQ_GHJ_PWR_VR"
CDS_LIB"mstr_discrete"
MATERIAL"EMPTY"
LOCATION"R9U4"
PART_NUMBER"G21796-047"
VALUE"49.9"
PACK_TYPE"0402"
WATTAGE"1/16W"
TOLERANCE"1%";
"A"
$PN"1"12;
"B"
$PN"2"64;
%"RES"
"1","(-225,2975)","0","mstr_discrete","I53";
;
CDS_SEC"1"
SEC_TYPE"0402"
SEC"1"
CDS_LOCATION"R1G7"
ROOM"VDDQ_GHJ_PWR_VR"
CDS_LIB"mstr_discrete"
PACK_TYPE"0402"
LOCATION"R1G7"
PART_NUMBER"G21796-009"
VALUE"150.0"
TOLERANCE"1%"
MATERIAL"CHIP"
WATTAGE"1/16W";
"B"
$PN"2"45;
"A"
$PN"1"64;
%"VCC_CORE"
"1","(-1175,3925)","0","mstr_symbols","I56";
;
CDS_LIB"mstr_symbols"
HDL_POWER"VR_FET_SW_P12V_STBY_PVDDQ_GHJ";
"A"13;
%"RES"
"2","(-1175,3700)","0","mstr_discrete","I57";
;
CDS_SEC"1"
SEC_TYPE"0402"
SEC"1"
ROOM"VDDQ_GHJ_PWR_VR"
CDS_LOCATION"R9U11"
CDS_LIB"mstr_discrete"
LOCATION"R9U11"
VALUE"100.0K"
TOLERANCE"1%"
PART_NUMBER"G21796-160"
PACK_TYPE"0402"
MATERIAL"CHIP"
WATTAGE"1/16W";
"A"
$PN"1"13;
"B"
$PN"2"66;
%"RES"
"2","(-1175,3350)","0","mstr_discrete","I58";
;
CDS_SEC"1"
SEC_TYPE"0402"
SEC"1"
ROOM"VDDQ_GHJ_PWR_VR"
CDS_LOCATION"R1G24"
CDS_LIB"mstr_discrete"
LOCATION"R1G24"
PART_NUMBER"G21796-003"
VALUE"1.5K"
PACK_TYPE"0402"
MATERIAL"CHIP"
WATTAGE"1/16W"
TOLERANCE"1%";
"A"
$PN"1"66;
"B"
$PN"2"14;
%"CAP"
"1","(-1400,3350)","2","mstr_discrete","I59";
;
CDS_SEC"1"
SEC_TYPE"0402LF"
SEC"1"
CDS_LIB"mstr_discrete"
ROOM"VDDQ_GHJ_PWR_VR"
CDS_LOCATION"C1G26"
LOCATION"C1G26"
PART_NUMBER"A36096-046"
VALUE"1000PF"
TOLERANCE"10%"
PACK_TYPE"0402LF"
VOLTAGE"50V"
MATERIAL"X7R";
"A"
$PN"1"66;
"B"
$PN"2"15;
%"GND"
"1","(-1175,3125)","0","mstr_symbols","I60";
;
SIZE"1B"
HDL_POWER"GND"
VOLTAGE"0"
CDS_LIB"mstr_symbols"
BODY_TYPE"PLUMBING"
ROOM"VDDQ_GHJ_PWR_VR";
"A\NAC"14;
%"GND"
"1","(-1400,3125)","0","mstr_symbols","I61";
;
HDL_POWER"GND"
SIZE"1B"
CDS_LIB"mstr_symbols"
VOLTAGE"0"
BODY_TYPE"PLUMBING"
ROOM"VDDQ_GHJ_PWR_VR";
"A\NAC"15;
%"PVCCIO_CPU1"
"1","(3925,3000)","0","mstr_symbols","I7";
;
HDL_POWER"PVCCIO_CPU1"
BODY_TYPE"PLUMBING"
CDS_LIB"mstr_symbols"
VOLTAGE"1.1V";
"G\NAC"16;
%"RES"
"2","(275,300)","0","mstr_discrete","I77";
;
CDS_SEC"1"
ROOM"VDDQ_GHJ_PWR_VR"
SEC_TYPE"0402"
SEC"1"
CDS_LOCATION"R1G23"
CDS_LIB"mstr_discrete"
PART_NUMBER"G21796-082"
WATTAGE"1/16W"
VALUE"4.02K"
LOCATION"R1G23"
TOLERANCE"1%"
MATERIAL"CHIP"
PACK_TYPE"0402";
"A"
$PN"1"50;
"B"
$PN"2"10;
%"RES"
"2","(625,300)","0","mstr_discrete","I78";
;
CDS_SEC"1"
SEC_TYPE"0402"
ROOM"VDDQ_GHJ_PWR_VR"
CDS_LIB"mstr_discrete"
SEC"1"
CDS_LOCATION"R1G22"
LOCATION"R1G22"
PART_NUMBER"G21796-297"
VALUE"5.36K"
TOLERANCE"1.0%"
PACK_TYPE"0402"
MATERIAL"CHIP"
WATTAGE"1/16W";
"A"
$PN"1"55;
"B"
$PN"2"9;
%"RES"
"2","(2200,3125)","0","mstr_discrete","I79";
;
CDS_SEC"1"
ROOM"RQ_PVDDQ_GHJ_VRHOT_LVT3_N"
SEC_TYPE"0402"
SEC"1"
CDS_LOCATION"R1G11"
CDS_LIB"mstr_discrete"
LOCATION"R1G11"
VALUE"1.00K"
WATTAGE"1/16W"
TOLERANCE"1%"
MATERIAL"CHIP"
PACK_TYPE"0402"
PART_NUMBER"G21796-026";
"A"
$PN"1"1;
"B"
$PN"2"25;
%"RES"
"2","(3925,2800)","0","mstr_discrete","I8";
;
CDS_SEC"1"
SEC_TYPE"0402"
SEC"1"
ROOM"VDDQ_GHJ_PWR_VR"
CDS_LOCATION"R9U3"
CDS_LIB"mstr_discrete"
PART_NUMBER"G21796-017"
VALUE"100.0"
WATTAGE"1/16W"
TOLERANCE"1%"
LOCATION"R9U3"
PACK_TYPE"0402"
MATERIAL"CHIP";
"A"
$PN"1"16;
"B"
$PN"2"27;
%"CAP"
"1","(3050,1000)","0","mstr_discrete","I80";
;
CDS_SEC"1"
ROOM"VDDQ_GHJ_PWR_VR"
CDS_LOCATION"C1G21"
SEC"1"
SEC_TYPE"0402LF"
CDS_LIB"mstr_discrete"
LOCATION"C1G21"
VALUE"1000PF"
VOLTAGE"50V"
MATERIAL"X7R"
PACK_TYPE"0402LF"
TOLERANCE"10%"
PART_NUMBER"A36096-046";
"A"
$PN"1"24;
"B"
$PN"2"17;
%"GND"
"1","(3050,700)","0","mstr_symbols","I81";
;
SIZE"1B"
HDL_POWER"GND"
BODY_TYPE"PLUMBING"
CDS_LIB"mstr_symbols"
VOLTAGE"0"
ROOM"VDDQ_GHJ_PWR_VR";
"A\NAC"17;
%"RES"
"1","(3475,2450)","0","mstr_discrete","I82";
;
CDS_SEC"1"
SEC_TYPE"0402"
SEC"1"
CDS_LIB"mstr_discrete"
CDS_LOCATION"R1G8"
PACK_TYPE"0402"
PART_NUMBER"G21796-074"
MATERIAL"CHIP"
TOLERANCE"1%"
LOCATION"R1G8"
VALUE"33.2"
WATTAGE"1/16W";
"B"
$PN"2"21;
"A"
$PN"1"25;
%"RES"
"1","(-1500,1500)","0","mstr_discrete","I84";
;
CDS_LIB"mstr_discrete"
$SEC"1"
CDS_SEC"1"
CDS_LOCATION"R9U7"
ROOM"PVCCIN_CPU0_VR"
MATERIAL"CHIP"
PACK_TYPE"0402"
LOCATION"R9U7"
PART_NUMBER"G21497-005"
TOLERANCE"5%"
WATTAGE"1/16W"
VALUE"0.0";
"B"
$PN"2"48;
"A"
$PN"1"68;
%"RES"
"2","(175,3425)","0","mstr_discrete","I85";
;
BOM_COST"SM_CONTROLLER"
CDS_SEC"1"
$SEC"1"
ROOM"BMC"
CDS_LOCATION"R9U8"
CDS_LIB"mstr_discrete"
MATERIAL"EMPTY"
LOCATION"R9U8"
PART_NUMBER"G21796-010"
VALUE"100.0K"
TOLERANCE"1%"
PACK_TYPE"0402"
WATTAGE"1/16W";
"A"
$PN"1"5;
"B"
$PN"2"48;
%"RES"
"1","(-1375,2625)","0","mstr_discrete","I87";
;
CDS_LOCATION"R1G28"
$SEC"1"
CDS_SEC"1"
ROOM"PVCCIN_CPU0_VR"
CDS_LIB"mstr_discrete"
PART_NUMBER"G21497-005"
LOCATION"R1G28"
MATERIAL"CHIP"
PACK_TYPE"0402"
TOLERANCE"5%"
VALUE"0.0"
WATTAGE"1/16W";
"B"
$PN"2"58;
"A"
$PN"1"65;
%"RES"
"1","(-600,2800)","0","mstr_discrete","I88";
;
CDS_LOCATION"R1G27"
CDS_SEC"1"
ROOM"PVCCIN_CPU0_VR"
$SEC"1"
CDS_LIB"mstr_discrete"
LOCATION"R1G27"
PART_NUMBER"G21497-005"
PACK_TYPE"0402"
MATERIAL"CHIP"
TOLERANCE"5%"
VALUE"0.0"
WATTAGE"1/16W";
"B"
$PN"2"59;
"A"
$PN"1"65;
%"PXM1310B"
"2","(1500,1800)","0","mstr_controller","I90";
;
CDS_SEC"1"
SEC"1"
SEC_TYPE"QFN"
PACK_TYPE"QFN"
CDS_LOCATION"EU1G2"
CDS_LIB"mstr_controller"
CDS_LMAN_SYM_OUTLINE"-400,900,400,-900"
LOCATION"EU1G2"
MATERIAL"IC"
PART_NUMBER"H89186-001";
"MP2"
$PN"18"31;
"MP1"
$PN"14"40;
"MP0"
$PN"13"28;
"AVREN"
$PN"10"48;
"AVRRDY"
$PN"9"24;
"IINSEN"
$PN"38"60;
"GND"
$PN"27"2;
"VD12"
$PN"40"41;
"VINSEN"
$PN"37"63;
"BVREF"
$PN"30"52;
"BVSEN"
$PN"29"53;
"AVREF"
$PN"20"19;
"AVSEN"
$PN"19"57;
"VALRT_N \B"
$PN"17"30;
"PINALRT_N \B"
$PN"12"39;
"VRHOT_N \B"
$PN"11"25;
"DNC<1>"
$PN"28"38;
"DNC<0>"
$PN"2"37;
"BIREF1"
$PN"31"51;
"BISEN1"
$PN"32"6;
"BTSEN"
$PN"34"56;
"VDD"
$PN"39"44;
"AIREF1"
$PN"21"58;
"AISEN1"
$PN"22"61;
"ATSEN"
$PN"35"49;
"AIREF2"
$PN"23"59;
"AISEN2"
$PN"24"62;
"XADDR2"
$PN"33"55;
"AIREF3"
$PN"25"47;
"AISEN3"
$PN"26"46;
"XADDR1"
$PN"36"50;
"RESET_N \B"
$PN"8"54;
"VDIO"
$PN"16"36;
"VCLK"
$PN"15"45;
"SCL"
$PN"7"35;
"SDA"
$PN"6"34;
"APWM3"
$PN"3"33;
"APWM2"
$PN"4"43;
"APWM1"
$PN"5"42;
"BPWM1"
$PN"1"32;
"THPAD"
$PN"41"2;
%"GND"
"1","(-325,125)","0","mstr_symbols","I91";
;
SIZE"1B"
HDL_POWER"GND"
VOLTAGE"0.0V"
CDS_LIB"mstr_symbols"
BODY_TYPE"PLUMBING";
"A\NAC"18;
%"CAP_A"
"1","(-325,450)","2","dev_discrete","I92";
;
CDS_LOCATION"C9U12"
ROOM"VDDQ_GHJ_PWR_VR"
CDS_SEC"1"
SEC_TYPE"0402V"
SEC"1"
CDS_LIB"dev_discrete"
TOLERANCE"10%"
VOLTAGE"16V"
MATERIAL"X7R"
LOCATION"C9U12"
PART_NUMBER"A36096-030"
VALUE"0.1UF"
PACK_TYPE"0402V";
"B"
$PN"2"18;
"A"
$PN"1"60;
END.
